(kicad_pcb
	(version 20260206)
	(generator "pcbnew")
	(generator_version "10.0")
	(general
		(thickness 1.6)
		(legacy_teardrops no)
	)
	(paper "A4")
	(title_block
		(title "v1-chassis-manager — T6M_CM_d_v01_1031_1645.brd")
		(comment 1 "Open CloudServer (Microsoft) / footprints 1584-1592 of 2512")
	)
	(layers
		(0 "F.Cu" signal "TOP")
		(4 "In1.Cu" signal "GND1")
		(6 "In2.Cu" signal "IN1")
		(8 "In3.Cu" signal "VCC1")
		(10 "In4.Cu" signal "VCC2")
		(12 "In5.Cu" signal "GND2")
		(14 "In6.Cu" signal "IN2")
		(16 "In7.Cu" signal "IN3")
		(18 "In8.Cu" signal "GND3")
		(2 "B.Cu" signal "BOTTOM")
		(9 "F.Adhes" user "F.Adhesive")
		(11 "B.Adhes" user "B.Adhesive")
		(13 "F.Paste" user "Package Geometry/Pastemask Top")
		(15 "B.Paste" user "Package Geometry/Pastemask Bottom")
		(5 "F.SilkS" user "Ref Des/Silkscreen Top")
		(7 "B.SilkS" user "Ref Des/Silkscreen Bottom")
		(1 "F.Mask" user "Board Geometry/Soldermask Top")
		(3 "B.Mask" user "Board Geometry/Soldermask Bottom")
		(17 "Dwgs.User" user "User.Drawings")
		(19 "Cmts.User" user "User.Comments")
		(21 "Eco1.User" user "User.Eco1")
		(23 "Eco2.User" user "User.Eco2")
		(25 "Edge.Cuts" user "Board Geometry/Outline")
		(27 "Margin" user)
		(31 "F.CrtYd" user "Package Geometry/Place Bound Top")
		(29 "B.CrtYd" user "Package Geometry/Place Bound Bottom")
		(35 "F.Fab" user "Ref Des/Assembly Top")
		(33 "B.Fab" user "Ref Des/Assembly Bottom")
	)
	(footprint ""
		(layer "B.Cu")
		(at 64.736472 -138.915648 180)
		(property "Reference" "C250"
			(at 38.965886 -54.703218 0)
			(unlocked yes)
			(layer "B.SilkS")
			(effects
				(font
					(size 0.7874 0.5842)
					(thickness 0.1524)
				)
				(justify left mirror)
			)
		)
		(property "Value" ""
			(at 0 0 0)
			(layer "B.Fab")
			(effects
				(font
					(size 1.27 1.27)
				)
				(justify mirror)
			)
		)
		(duplicate_pad_numbers_are_jumpers no)
		(fp_line
			(start 0.7874 0.4064)
			(end 0.7874 -0.4064)
			(stroke
				(width 0.1524)
				(type default)
			)
			(layer "B.SilkS")
		)
		(fp_line
			(start 0.7874 -0.4064)
			(end -0.7874 -0.4064)
			(stroke
				(width 0.1524)
				(type default)
			)
			(layer "B.SilkS")
		)
		(fp_line
			(start 0 0.381)
			(end 0 -0.381)
			(stroke
				(width 0.1524)
				(type default)
			)
			(layer "B.SilkS")
		)
		(fp_line
			(start -0.7874 0.4064)
			(end 0.7874 0.4064)
			(stroke
				(width 0.1524)
				(type default)
			)
			(layer "B.SilkS")
		)
		(fp_line
			(start -0.7874 -0.4064)
			(end -0.7874 0.4064)
			(stroke
				(width 0.1524)
				(type default)
			)
			(layer "B.SilkS")
		)
		(fp_poly
			(pts
				(xy 0.5334 0.254) (xy 0.635 0.254) (xy 0.635 0.2286) (xy 0.635 -0.254) (xy 0.5334 -0.254) (xy 0.5334 -0.2794)
				(xy -0.5334 -0.2794) (xy -0.5334 -0.254) (xy -0.635 -0.254) (xy -0.635 0.254) (xy -0.5334 0.254)
				(xy -0.5334 0.2794) (xy 0.508 0.2794) (xy 0.5334 0.2794)
			)
			(stroke
				(width 0)
				(type default)
			)
			(fill no)
			(layer "B.CrtYd")
		)
		(pad "1" smd rect
			(at -0.40005 0)
			(size 0.4572 0.508)
			(layers "B.Cu" "B.Mask" "B.Paste")
			(net "P3V3_NODE1")
		)
		(pad "2" smd rect
			(at 0.40005 0)
			(size 0.4572 0.508)
			(layers "B.Cu" "B.Mask" "B.Paste")
			(net "GND")
		)
	)
	(footprint ""
		(layer "B.Cu")
		(at 132.978652 -137.92835 180)
		(property "Reference" "C895"
			(at -4.032504 0.06477 0)
			(unlocked yes)
			(layer "B.SilkS")
			(effects
				(font
					(size 0.7874 0.5842)
					(thickness 0.1524)
				)
				(justify left mirror)
			)
		)
		(property "Value" ""
			(at 0 0 0)
			(layer "B.Fab")
			(effects
				(font
					(size 1.27 1.27)
				)
				(justify mirror)
			)
		)
		(duplicate_pad_numbers_are_jumpers no)
		(fp_line
			(start 0.7874 0.4064)
			(end 0.7874 -0.4064)
			(stroke
				(width 0.1524)
				(type default)
			)
			(layer "B.SilkS")
		)
		(fp_line
			(start 0.7874 -0.4064)
			(end -0.7874 -0.4064)
			(stroke
				(width 0.1524)
				(type default)
			)
			(layer "B.SilkS")
		)
		(fp_line
			(start 0 0.381)
			(end 0 -0.381)
			(stroke
				(width 0.1524)
				(type default)
			)
			(layer "B.SilkS")
		)
		(fp_line
			(start -0.7874 0.4064)
			(end 0.7874 0.4064)
			(stroke
				(width 0.1524)
				(type default)
			)
			(layer "B.SilkS")
		)
		(fp_line
			(start -0.7874 -0.4064)
			(end -0.7874 0.4064)
			(stroke
				(width 0.1524)
				(type default)
			)
			(layer "B.SilkS")
		)
		(fp_poly
			(pts
				(xy 0.5334 0.254) (xy 0.635 0.254) (xy 0.635 0.2286) (xy 0.635 -0.254) (xy 0.5334 -0.254) (xy 0.5334 -0.2794)
				(xy -0.5334 -0.2794) (xy -0.5334 -0.254) (xy -0.635 -0.254) (xy -0.635 0.254) (xy -0.5334 0.254)
				(xy -0.5334 0.2794) (xy 0.508 0.2794) (xy 0.5334 0.2794)
			)
			(stroke
				(width 0)
				(type default)
			)
			(fill no)
			(layer "B.CrtYd")
		)
		(pad "1" smd rect
			(at -0.40005 0)
			(size 0.4572 0.508)
			(layers "B.Cu" "B.Mask" "B.Paste")
			(net "P1V0_PCI_SW_A")
		)
		(pad "2" smd rect
			(at 0.40005 0)
			(size 0.4572 0.508)
			(layers "B.Cu" "B.Mask" "B.Paste")
			(net "GND")
		)
	)
	(footprint ""
		(layer "B.Cu")
		(at 105.191814 -108.92282)
		(property "Reference" "PC105"
			(at -3.119374 -0.235712 0)
			(unlocked yes)
			(layer "B.SilkS")
			(effects
				(font
					(size 0.7874 0.5842)
					(thickness 0.1524)
				)
				(justify left mirror)
			)
		)
		(property "Value" ""
			(at 0 0 0)
			(layer "B.Fab")
			(effects
				(font
					(size 1.27 1.27)
				)
				(justify mirror)
			)
		)
		(duplicate_pad_numbers_are_jumpers no)
		(fp_line
			(start -1.905 -0.8636)
			(end -1.905 0.8636)
			(stroke
				(width 0.1524)
				(type default)
			)
			(layer "B.SilkS")
		)
		(fp_line
			(start -1.905 0.8636)
			(end 1.905 0.8636)
			(stroke
				(width 0.1524)
				(type default)
			)
			(layer "B.SilkS")
		)
		(fp_line
			(start 0 0.8382)
			(end 0 -0.8382)
			(stroke
				(width 0.1524)
				(type default)
			)
			(layer "B.SilkS")
		)
		(fp_line
			(start 1.905 -0.8636)
			(end -1.905 -0.8636)
			(stroke
				(width 0.1524)
				(type default)
			)
			(layer "B.SilkS")
		)
		(fp_line
			(start 1.905 0.8636)
			(end 1.905 -0.8636)
			(stroke
				(width 0.1524)
				(type default)
			)
			(layer "B.SilkS")
		)
		(fp_rect
			(start 1.524 0.7366)
			(end -1.524 -0.7366)
			(stroke
				(width 0)
				(type default)
			)
			(fill no)
			(layer "B.CrtYd")
		)
		(pad "1" smd rect
			(at -0.94996 0 180)
			(size 1.1176 1.3716)
			(layers "B.Cu" "B.Mask" "B.Paste")
			(net "GND")
		)
		(pad "2" smd rect
			(at 0.94996 0 180)
			(size 1.1176 1.3716)
			(layers "B.Cu" "B.Mask" "B.Paste")
			(net "PV_VCCP_NODE1")
		)
	)
	(footprint ""
		(layer "B.Cu")
		(at 169.554652 -104.84739 90)
		(property "Reference" "C375"
			(at 1.423416 6.014212 270)
			(unlocked yes)
			(layer "B.SilkS")
			(effects
				(font
					(size 0.7874 0.5842)
					(thickness 0.1524)
				)
				(justify left mirror)
			)
		)
		(property "Value" ""
			(at 0 0 90)
			(layer "B.Fab")
			(effects
				(font
					(size 1.27 1.27)
				)
				(justify mirror)
			)
		)
		(duplicate_pad_numbers_are_jumpers no)
		(fp_line
			(start 0.7874 -0.4064)
			(end -0.7874 -0.4064)
			(stroke
				(width 0.1524)
				(type default)
			)
			(layer "B.SilkS")
		)
		(fp_line
			(start -0.7874 -0.4064)
			(end -0.7874 0.4064)
			(stroke
				(width 0.1524)
				(type default)
			)
			(layer "B.SilkS")
		)
		(fp_line
			(start 0 0.381)
			(end 0 -0.381)
			(stroke
				(width 0.1524)
				(type default)
			)
			(layer "B.SilkS")
		)
		(fp_line
			(start 0.7874 0.4064)
			(end 0.7874 -0.4064)
			(stroke
				(width 0.1524)
				(type default)
			)
			(layer "B.SilkS")
		)
		(fp_line
			(start -0.7874 0.4064)
			(end 0.7874 0.4064)
			(stroke
				(width 0.1524)
				(type default)
			)
			(layer "B.SilkS")
		)
		(fp_poly
			(pts
				(xy 0.5334 0.254) (xy 0.635 0.254) (xy 0.635 0.2286) (xy 0.635 -0.254) (xy 0.5334 -0.254) (xy 0.5334 -0.2794)
				(xy -0.5334 -0.2794) (xy -0.5334 -0.254) (xy -0.635 -0.254) (xy -0.635 0.254) (xy -0.5334 0.254)
				(xy -0.5334 0.2794) (xy 0.508 0.2794) (xy 0.5334 0.2794)
			)
			(stroke
				(width 0)
				(type default)
			)
			(fill no)
			(layer "B.CrtYd")
		)
		(pad "1" smd rect
			(at -0.40005 0 270)
			(size 0.4572 0.508)
			(layers "B.Cu" "B.Mask" "B.Paste")
			(net "GND")
		)
		(pad "2" smd rect
			(at 0.40005 0 270)
			(size 0.4572 0.508)
			(layers "B.Cu" "B.Mask" "B.Paste")
			(net "P1V05_NODE1")
		)
	)
	(footprint ""
		(layer "B.Cu")
		(at 154.06116 -173.521624)
		(property "Reference" "R748"
			(at -1.545844 12.970002 0)
			(unlocked yes)
			(layer "B.SilkS")
			(effects
				(font
					(size 0.7874 0.5842)
					(thickness 0.1524)
				)
				(justify left mirror)
			)
		)
		(property "Value" ""
			(at 0 0 0)
			(layer "B.Fab")
			(effects
				(font
					(size 1.27 1.27)
				)
				(justify mirror)
			)
		)
		(duplicate_pad_numbers_are_jumpers no)
		(fp_line
			(start -0.7874 -0.4064)
			(end -0.7874 0.4064)
			(stroke
				(width 0.1524)
				(type default)
			)
			(layer "B.SilkS")
		)
		(fp_line
			(start -0.7874 0.4064)
			(end 0.7874 0.4064)
			(stroke
				(width 0.1524)
				(type default)
			)
			(layer "B.SilkS")
		)
		(fp_line
			(start 0.7874 -0.4064)
			(end -0.7874 -0.4064)
			(stroke
				(width 0.1524)
				(type default)
			)
			(layer "B.SilkS")
		)
		(fp_line
			(start 0.7874 0.4064)
			(end 0.7874 -0.4064)
			(stroke
				(width 0.1524)
				(type default)
			)
			(layer "B.SilkS")
		)
		(fp_poly
			(pts
				(xy 0.508 0.2794) (xy 0.508 0.2286) (xy 0.635 0.2286) (xy 0.635 -0.254) (xy 0.5334 -0.254) (xy 0.5334 -0.2794)
				(xy -0.5334 -0.2794) (xy -0.5334 -0.254) (xy -0.635 -0.254) (xy -0.635 0.254) (xy -0.5334 0.254)
				(xy -0.5334 0.2794)
			)
			(stroke
				(width 0)
				(type default)
			)
			(fill no)
			(layer "B.CrtYd")
		)
		(pad "1" smd rect
			(at -0.40005 0 180)
			(size 0.4572 0.508)
			(layers "B.Cu" "B.Mask" "B.Paste")
			(net "T12_NODE3_EN")
		)
		(pad "2" smd rect
			(at 0.40005 0 180)
			(size 0.4572 0.508)
			(layers "B.Cu" "B.Mask" "B.Paste")
			(net "P5V_NODE1")
		)
	)
	(footprint ""
		(layer "B.Cu")
		(at 121.14784 -45.817282)
		(property "Reference" "R95"
			(at -1.094486 -0.749808 0)
			(unlocked yes)
			(layer "B.SilkS")
			(effects
				(font
					(size 0.7874 0.5842)
					(thickness 0.1524)
				)
				(justify left mirror)
			)
		)
		(property "Value" ""
			(at 0 0 0)
			(layer "B.Fab")
			(effects
				(font
					(size 1.27 1.27)
				)
				(justify mirror)
			)
		)
		(duplicate_pad_numbers_are_jumpers no)
		(fp_line
			(start -0.7874 -0.4064)
			(end -0.7874 0.4064)
			(stroke
				(width 0.1524)
				(type default)
			)
			(layer "B.SilkS")
		)
		(fp_line
			(start -0.7874 0.4064)
			(end 0.7874 0.4064)
			(stroke
				(width 0.1524)
				(type default)
			)
			(layer "B.SilkS")
		)
		(fp_line
			(start 0.7874 -0.4064)
			(end -0.7874 -0.4064)
			(stroke
				(width 0.1524)
				(type default)
			)
			(layer "B.SilkS")
		)
		(fp_line
			(start 0.7874 0.4064)
			(end 0.7874 -0.4064)
			(stroke
				(width 0.1524)
				(type default)
			)
			(layer "B.SilkS")
		)
		(fp_poly
			(pts
				(xy 0.508 0.2794) (xy 0.508 0.2286) (xy 0.635 0.2286) (xy 0.635 -0.254) (xy 0.5334 -0.254) (xy 0.5334 -0.2794)
				(xy -0.5334 -0.2794) (xy -0.5334 -0.254) (xy -0.635 -0.254) (xy -0.635 0.254) (xy -0.5334 0.254)
				(xy -0.5334 0.2794)
			)
			(stroke
				(width 0)
				(type default)
			)
			(fill no)
			(layer "B.CrtYd")
		)
		(pad "1" smd rect
			(at -0.40005 0 180)
			(size 0.4572 0.508)
			(layers "B.Cu" "B.Mask" "B.Paste")
			(net "IRQ_CPU_NODE1_SERIAL")
		)
		(pad "2" smd rect
			(at 0.40005 0 180)
			(size 0.4572 0.508)
			(layers "B.Cu" "B.Mask" "B.Paste")
			(net "IRQ_CPU_NODE1_SERIAL_SIO")
		)
	)
	(footprint ""
		(layer "B.Cu")
		(at 26.432256 -157.713172)
		(property "Reference" "C513"
			(at -2.96926 -0.13335 0)
			(unlocked yes)
			(layer "B.SilkS")
			(effects
				(font
					(size 0.7874 0.5842)
					(thickness 0.1524)
				)
				(justify left mirror)
			)
		)
		(property "Value" ""
			(at 0 0 0)
			(layer "B.Fab")
			(effects
				(font
					(size 1.27 1.27)
				)
				(justify mirror)
			)
		)
		(duplicate_pad_numbers_are_jumpers no)
		(fp_line
			(start -0.7874 -0.4064)
			(end -0.7874 0.4064)
			(stroke
				(width 0.1524)
				(type default)
			)
			(layer "B.SilkS")
		)
		(fp_line
			(start -0.7874 0.4064)
			(end 0.7874 0.4064)
			(stroke
				(width 0.1524)
				(type default)
			)
			(layer "B.SilkS")
		)
		(fp_line
			(start 0 0.381)
			(end 0 -0.381)
			(stroke
				(width 0.1524)
				(type default)
			)
			(layer "B.SilkS")
		)
		(fp_line
			(start 0.7874 -0.4064)
			(end -0.7874 -0.4064)
			(stroke
				(width 0.1524)
				(type default)
			)
			(layer "B.SilkS")
		)
		(fp_line
			(start 0.7874 0.4064)
			(end 0.7874 -0.4064)
			(stroke
				(width 0.1524)
				(type default)
			)
			(layer "B.SilkS")
		)
		(fp_poly
			(pts
				(xy 0.5334 0.254) (xy 0.635 0.254) (xy 0.635 0.2286) (xy 0.635 -0.254) (xy 0.5334 -0.254) (xy 0.5334 -0.2794)
				(xy -0.5334 -0.2794) (xy -0.5334 -0.254) (xy -0.635 -0.254) (xy -0.635 0.254) (xy -0.5334 0.254)
				(xy -0.5334 0.2794) (xy 0.508 0.2794) (xy 0.5334 0.2794)
			)
			(stroke
				(width 0)
				(type default)
			)
			(fill no)
			(layer "B.CrtYd")
		)
		(pad "1" smd rect
			(at -0.40005 0 180)
			(size 0.4572 0.508)
			(layers "B.Cu" "B.Mask" "B.Paste")
			(net "P1V9_LAN1")
		)
		(pad "2" smd rect
			(at 0.40005 0 180)
			(size 0.4572 0.508)
			(layers "B.Cu" "B.Mask" "B.Paste")
			(net "GND")
		)
	)
	(footprint ""
		(layer "B.Cu")
		(at 84.827872 -165.979348 90)
		(property "Reference" "U73"
			(at -18.702274 27.113738 0)
			(unlocked yes)
			(layer "B.SilkS")
			(effects
				(font
					(size 0.7874 0.5842)
					(thickness 0.1524)
				)
				(justify left mirror)
			)
		)
		(property "Value" ""
			(at 0 0 90)
			(layer "B.Fab")
			(effects
				(font
					(size 1.27 1.27)
				)
				(justify mirror)
			)
		)
		(duplicate_pad_numbers_are_jumpers no)
		(fp_line
			(start 2.5654 -2.0066)
			(end -2.5654 -2.0066)
			(stroke
				(width 0.1524)
				(type default)
			)
			(layer "B.SilkS")
		)
		(fp_line
			(start -2.5654 -2.0066)
			(end -2.5654 2.0066)
			(stroke
				(width 0.1524)
				(type default)
			)
			(layer "B.SilkS")
		)
		(fp_line
			(start 2.5654 -0.5842)
			(end 2.5654 -2.0066)
			(stroke
				(width 0.1524)
				(type default)
			)
			(layer "B.SilkS")
		)
		(fp_line
			(start 1.9812 0)
			(end 2.5654 -0.5842)
			(stroke
				(width 0.1524)
				(type default)
			)
			(layer "B.SilkS")
		)
		(fp_line
			(start 2.5654 0.5842)
			(end 1.9812 0)
			(stroke
				(width 0.1524)
				(type default)
			)
			(layer "B.SilkS")
		)
		(fp_line
			(start 2.5654 2.0066)
			(end 2.5654 0.5842)
			(stroke
				(width 0.1524)
				(type default)
			)
			(layer "B.SilkS")
		)
		(fp_line
			(start -2.5654 2.0066)
			(end 2.5654 2.0066)
			(stroke
				(width 0.1524)
				(type default)
			)
			(layer "B.SilkS")
		)
		(fp_circle
			(center 2.032 1.524)
			(end 2.032 1.778)
			(stroke
				(width 0.1524)
				(type default)
			)
			(fill no)
			(layer "B.SilkS")
		)
		(fp_rect
			(start 2.5654 3.6703)
			(end -2.5654 -3.6703)
			(stroke
				(width 0)
				(type default)
			)
			(fill no)
			(layer "B.CrtYd")
		)
		(pad "1" smd rect
			(at 2.275078 2.921 270)
			(size 0.3556 1.4986)
			(layers "B.Cu" "B.Mask" "B.Paste")
			(net "UART_SW_S0_N")
		)
		(pad "2" smd rect
			(at 1.625092 2.921 270)
			(size 0.3556 1.4986)
			(layers "B.Cu" "B.Mask" "B.Paste")
			(net "UART_SW_S1_N")
		)
		(pad "3" smd rect
			(at 0.975106 2.921 270)
			(size 0.3556 1.4986)
			(layers "B.Cu" "B.Mask" "B.Paste")
			(net "SDC_RST_N")
		)
		(pad "4" smd rect
			(at 0.32512 2.921 270)
			(size 0.3556 1.4986)
			(layers "B.Cu" "B.Mask" "B.Paste")
			(net "GND")
		)
		(pad "5" smd rect
			(at -0.32512 2.921 270)
			(size 0.3556 1.4986)
			(layers "B.Cu" "B.Mask" "B.Paste")
			(net "UART_SW_S2_N")
		)
		(pad "6" smd rect
			(at -0.975106 2.921 270)
			(size 0.3556 1.4986)
			(layers "B.Cu" "B.Mask" "B.Paste")
			(net "UART_SW_S3_N")
		)
		(pad "7" smd rect
			(at -1.625092 2.921 270)
			(size 0.3556 1.4986)
			(layers "B.Cu" "B.Mask" "B.Paste")
			(net "I2C_SDC_SDA")
		)
		(pad "8" smd rect
			(at -2.275078 2.921 270)
			(size 0.3556 1.4986)
			(layers "B.Cu" "B.Mask" "B.Paste")
			(net "I2C_SDC_SCL")
		)
		(pad "9" smd rect
			(at -2.275078 -2.921 270)
			(size 0.3556 1.4986)
			(layers "B.Cu" "B.Mask" "B.Paste")
			(net "UART_SDC_TX")
		)
		(pad "10" smd rect
			(at -1.625092 -2.921 270)
			(size 0.3556 1.4986)
			(layers "B.Cu" "B.Mask" "B.Paste")
			(net "UART_SDC_RX")
		)
		(pad "11" smd rect
			(at -0.975106 -2.921 270)
			(size 0.3556 1.4986)
			(layers "B.Cu" "B.Mask" "B.Paste")
			(net "CPLD_WDT2_R")
		)
		(pad "12" smd rect
			(at -0.32512 -2.921 270)
			(size 0.3556 1.4986)
			(layers "B.Cu" "B.Mask" "B.Paste")
			(net "P3V3_NODE1")
		)
		(pad "13" smd rect
			(at 0.32512 -2.921 270)
			(size 0.3556 1.4986)
			(layers "B.Cu" "B.Mask" "B.Paste")
			(net "SDC_WAKEUP")
		)
		(pad "14" smd rect
			(at 0.975106 -2.921 270)
			(size 0.3556 1.4986)
			(layers "B.Cu" "B.Mask" "B.Paste")
			(net "UART_SW_S5_N")
		)
		(pad "15" smd rect
			(at 1.625092 -2.921 270)
			(size 0.3556 1.4986)
			(layers "B.Cu" "B.Mask" "B.Paste")
			(net "UART_SW_S4_N")
		)
		(pad "16" smd rect
			(at 2.275078 -2.921 270)
			(size 0.3556 1.4986)
			(layers "B.Cu" "B.Mask" "B.Paste")
			(net "CM_CABLE_DET_N")
		)
	)
	(footprint ""
		(layer "B.Cu")
		(at 127.508 -59.436 90)
		(property "Reference" "R1328"
			(at 1.143 -0.02667 270)
			(unlocked yes)
			(layer "B.SilkS")
			(effects
				(font
					(size 0.7874 0.5842)
					(thickness 0.1524)
				)
				(justify left mirror)
			)
		)
		(property "Value" ""
			(at 0 0 90)
			(layer "B.Fab")
			(effects
				(font
					(size 1.27 1.27)
				)
				(justify mirror)
			)
		)
		(duplicate_pad_numbers_are_jumpers no)
		(fp_line
			(start 0.7874 -0.4064)
			(end -0.7874 -0.4064)
			(stroke
				(width 0.1524)
				(type default)
			)
			(layer "B.SilkS")
		)
		(fp_line
			(start -0.7874 -0.4064)
			(end -0.7874 0.4064)
			(stroke
				(width 0.1524)
				(type default)
			)
			(layer "B.SilkS")
		)
		(fp_line
			(start 0.7874 0.4064)
			(end 0.7874 -0.4064)
			(stroke
				(width 0.1524)
				(type default)
			)
			(layer "B.SilkS")
		)
		(fp_line
			(start -0.7874 0.4064)
			(end 0.7874 0.4064)
			(stroke
				(width 0.1524)
				(type default)
			)
			(layer "B.SilkS")
		)
		(fp_poly
			(pts
				(xy 0.508 0.2794) (xy 0.508 0.2286) (xy 0.635 0.2286) (xy 0.635 -0.254) (xy 0.5334 -0.254) (xy 0.5334 -0.2794)
				(xy -0.5334 -0.2794) (xy -0.5334 -0.254) (xy -0.635 -0.254) (xy -0.635 0.254) (xy -0.5334 0.254)
				(xy -0.5334 0.2794)
			)
			(stroke
				(width 0)
				(type default)
			)
			(fill no)
			(layer "B.CrtYd")
		)
		(pad "1" smd rect
			(at -0.40005 0 270)
			(size 0.4572 0.508)
			(layers "B.Cu" "B.Mask" "B.Paste")
			(net "UART_RI_P3_N")
		)
		(pad "2" smd rect
			(at 0.40005 0 270)
			(size 0.4572 0.508)
			(layers "B.Cu" "B.Mask" "B.Paste")
			(net "GND")
		)
	)
)
